(kicad_pcb
	(version 20260206)
	(generator "pcbnew")
	(generator_version "10.0")
	(general
		(thickness 1.6)
		(legacy_teardrops no)
	)
	(paper "A4")
	(title_block
		(title "v1-chassis-manager — T6M_CM_d_v01_1031_1645.brd")
		(comment 1 "Open CloudServer (Microsoft) / footprints 1181-1191 of 2512")
	)
	(layers
		(0 "F.Cu" signal "TOP")
		(4 "In1.Cu" signal "GND1")
		(6 "In2.Cu" signal "IN1")
		(8 "In3.Cu" signal "VCC1")
		(10 "In4.Cu" signal "VCC2")
		(12 "In5.Cu" signal "GND2")
		(14 "In6.Cu" signal "IN2")
		(16 "In7.Cu" signal "IN3")
		(18 "In8.Cu" signal "GND3")
		(2 "B.Cu" signal "BOTTOM")
		(9 "F.Adhes" user "F.Adhesive")
		(11 "B.Adhes" user "B.Adhesive")
		(13 "F.Paste" user "Package Geometry/Pastemask Top")
		(15 "B.Paste" user "Package Geometry/Pastemask Bottom")
		(5 "F.SilkS" user "Ref Des/Silkscreen Top")
		(7 "B.SilkS" user "Ref Des/Silkscreen Bottom")
		(1 "F.Mask" user "Board Geometry/Soldermask Top")
		(3 "B.Mask" user "Board Geometry/Soldermask Bottom")
		(17 "Dwgs.User" user "User.Drawings")
		(19 "Cmts.User" user "User.Comments")
		(21 "Eco1.User" user "User.Eco1")
		(23 "Eco2.User" user "User.Eco2")
		(25 "Edge.Cuts" user "Board Geometry/Outline")
		(27 "Margin" user)
		(31 "F.CrtYd" user "Package Geometry/Place Bound Top")
		(29 "B.CrtYd" user "Package Geometry/Place Bound Bottom")
		(35 "F.Fab" user "Ref Des/Assembly Top")
		(33 "B.Fab" user "Ref Des/Assembly Bottom")
	)
	(footprint ""
		(layer "F.Cu")
		(at 133.71576 -108.370624 90)
		(property "Reference" "R11"
			(at -6.585204 0.466852 90)
			(unlocked yes)
			(layer "F.SilkS")
			(effects
				(font
					(size 0.7874 0.5842)
					(thickness 0.1524)
				)
				(justify left)
			)
		)
		(property "Value" ""
			(at 0 0 90)
			(layer "F.Fab")
			(effects
				(font
					(size 1.27 1.27)
				)
			)
		)
		(duplicate_pad_numbers_are_jumpers no)
		(fp_line
			(start 0.7874 -0.4064)
			(end 0.7874 0.4064)
			(stroke
				(width 0.1524)
				(type default)
			)
			(layer "F.SilkS")
		)
		(fp_line
			(start -0.7874 -0.4064)
			(end 0.7874 -0.4064)
			(stroke
				(width 0.1524)
				(type default)
			)
			(layer "F.SilkS")
		)
		(fp_line
			(start 0.7874 0.4064)
			(end -0.7874 0.4064)
			(stroke
				(width 0.1524)
				(type default)
			)
			(layer "F.SilkS")
		)
		(fp_line
			(start -0.7874 0.4064)
			(end -0.7874 -0.4064)
			(stroke
				(width 0.1524)
				(type default)
			)
			(layer "F.SilkS")
		)
		(fp_poly
			(pts
				(xy -0.508 0.2794) (xy -0.508 0.2286) (xy -0.635 0.2286) (xy -0.635 -0.254) (xy -0.5334 -0.254)
				(xy -0.5334 -0.2794) (xy 0.5334 -0.2794) (xy 0.5334 -0.254) (xy 0.635 -0.254) (xy 0.635 0.254) (xy 0.5334 0.254)
				(xy 0.5334 0.2794)
			)
			(stroke
				(width 0)
				(type default)
			)
			(fill no)
			(layer "F.CrtYd")
		)
		(pad "1" smd rect
			(at 0.40005 0 90)
			(size 0.4572 0.508)
			(layers "F.Cu" "F.Mask" "F.Paste")
			(net "CLP_ITP_EN_NODE1")
		)
		(pad "2" smd rect
			(at -0.40005 0 90)
			(size 0.4572 0.508)
			(layers "F.Cu" "F.Mask" "F.Paste")
			(net "P3V3_CLK_NODE1")
		)
	)
	(footprint ""
		(layer "F.Cu")
		(at 155.999688 -178.689254 -90)
		(property "Reference" "R1167"
			(at -1.69926 -1.103884 90)
			(unlocked yes)
			(layer "F.SilkS")
			(effects
				(font
					(size 0.7874 0.5842)
					(thickness 0.1524)
				)
				(justify left)
			)
		)
		(property "Value" ""
			(at 0 0 270)
			(layer "F.Fab")
			(effects
				(font
					(size 1.27 1.27)
				)
			)
		)
		(duplicate_pad_numbers_are_jumpers no)
		(fp_line
			(start -0.7874 0.406146)
			(end -0.7874 -0.406146)
			(stroke
				(width 0.1524)
				(type default)
			)
			(layer "F.SilkS")
		)
		(fp_line
			(start 0.7874 0.406146)
			(end -0.7874 0.406146)
			(stroke
				(width 0.1524)
				(type default)
			)
			(layer "F.SilkS")
		)
		(fp_line
			(start -0.7874 -0.406146)
			(end 0.7874 -0.406146)
			(stroke
				(width 0.1524)
				(type default)
			)
			(layer "F.SilkS")
		)
		(fp_line
			(start 0.7874 -0.406146)
			(end 0.7874 0.406146)
			(stroke
				(width 0.1524)
				(type default)
			)
			(layer "F.SilkS")
		)
		(fp_poly
			(pts
				(xy -0.508 0.2794) (xy -0.508 0.2286) (xy -0.635 0.2286) (xy -0.635 -0.254) (xy -0.5334 -0.254)
				(xy -0.5334 -0.2794) (xy 0.5334 -0.2794) (xy 0.5334 -0.254) (xy 0.635 -0.254) (xy 0.635 0.254) (xy 0.5334 0.254)
				(xy 0.5334 0.2794)
			)
			(stroke
				(width 0)
				(type default)
			)
			(fill no)
			(layer "F.CrtYd")
		)
		(pad "1" smd rect
			(at 0.40005 0 270)
			(size 0.4572 0.508)
			(layers "F.Cu" "F.Mask" "F.Paste")
			(net "CPLD_UART_RX_P3_R")
		)
		(pad "2" smd rect
			(at -0.40005 0 270)
			(size 0.4572 0.508)
			(layers "F.Cu" "F.Mask" "F.Paste")
			(net "CPLD_UART_RX_P3")
		)
	)
	(footprint ""
		(layer "F.Cu")
		(at 136.125966 -55.324502 90)
		(property "Reference" "R1135"
			(at 0.936498 -0.260096 90)
			(unlocked yes)
			(layer "F.SilkS")
			(effects
				(font
					(size 0.7874 0.5842)
					(thickness 0.1524)
				)
				(justify left)
			)
		)
		(property "Value" ""
			(at 0 0 90)
			(layer "F.Fab")
			(effects
				(font
					(size 1.27 1.27)
				)
			)
		)
		(duplicate_pad_numbers_are_jumpers no)
		(fp_line
			(start 0.7874 -0.4064)
			(end 0.7874 0.4064)
			(stroke
				(width 0.1524)
				(type default)
			)
			(layer "F.SilkS")
		)
		(fp_line
			(start -0.7874 -0.4064)
			(end 0.7874 -0.4064)
			(stroke
				(width 0.1524)
				(type default)
			)
			(layer "F.SilkS")
		)
		(fp_line
			(start 0.7874 0.4064)
			(end -0.7874 0.4064)
			(stroke
				(width 0.1524)
				(type default)
			)
			(layer "F.SilkS")
		)
		(fp_line
			(start -0.7874 0.4064)
			(end -0.7874 -0.4064)
			(stroke
				(width 0.1524)
				(type default)
			)
			(layer "F.SilkS")
		)
		(fp_poly
			(pts
				(xy -0.508 0.2794) (xy -0.508 0.2286) (xy -0.635 0.2286) (xy -0.635 -0.254) (xy -0.5334 -0.254)
				(xy -0.5334 -0.2794) (xy 0.5334 -0.2794) (xy 0.5334 -0.254) (xy 0.635 -0.254) (xy 0.635 0.254) (xy 0.5334 0.254)
				(xy 0.5334 0.2794)
			)
			(stroke
				(width 0)
				(type default)
			)
			(fill no)
			(layer "F.CrtYd")
		)
		(pad "1" smd rect
			(at 0.40005 0 90)
			(size 0.4572 0.508)
			(layers "F.Cu" "F.Mask" "F.Paste")
			(net "GND")
		)
		(pad "2" smd rect
			(at -0.40005 0 90)
			(size 0.4572 0.508)
			(layers "F.Cu" "F.Mask" "F.Paste")
			(net "UART_TX_P3_R")
		)
	)
	(footprint ""
		(layer "F.Cu")
		(at 88.24976 -185.205624 -90)
		(property "Reference" "R948"
			(at -4.198112 2.110486 90)
			(unlocked yes)
			(layer "F.SilkS")
			(effects
				(font
					(size 0.7874 0.5842)
					(thickness 0.1524)
				)
				(justify left)
			)
		)
		(property "Value" ""
			(at 0 0 270)
			(layer "F.Fab")
			(effects
				(font
					(size 1.27 1.27)
				)
			)
		)
		(duplicate_pad_numbers_are_jumpers no)
		(fp_line
			(start -0.7874 0.4064)
			(end -0.7874 -0.4064)
			(stroke
				(width 0.1524)
				(type default)
			)
			(layer "F.SilkS")
		)
		(fp_line
			(start 0.7874 0.4064)
			(end -0.7874 0.4064)
			(stroke
				(width 0.1524)
				(type default)
			)
			(layer "F.SilkS")
		)
		(fp_line
			(start -0.7874 -0.4064)
			(end 0.7874 -0.4064)
			(stroke
				(width 0.1524)
				(type default)
			)
			(layer "F.SilkS")
		)
		(fp_line
			(start 0.7874 -0.4064)
			(end 0.7874 0.4064)
			(stroke
				(width 0.1524)
				(type default)
			)
			(layer "F.SilkS")
		)
		(fp_poly
			(pts
				(xy -0.508 0.2794) (xy -0.508 0.2286) (xy -0.635 0.2286) (xy -0.635 -0.254) (xy -0.5334 -0.254)
				(xy -0.5334 -0.2794) (xy 0.5334 -0.2794) (xy 0.5334 -0.254) (xy 0.635 -0.254) (xy 0.635 0.254) (xy 0.5334 0.254)
				(xy 0.5334 0.2794)
			)
			(stroke
				(width 0)
				(type default)
			)
			(fill no)
			(layer "F.CrtYd")
		)
		(pad "1" smd rect
			(at 0.40005 0 270)
			(size 0.4572 0.508)
			(layers "F.Cu" "F.Mask" "F.Paste")
			(net "UART_T6_NODE3_TXD")
		)
		(pad "2" smd rect
			(at -0.40005 0 270)
			(size 0.4572 0.508)
			(layers "F.Cu" "F.Mask" "F.Paste")
			(net "UART_T6_NODE3_TXD_R")
		)
	)
	(footprint ""
		(layer "F.Cu")
		(at 47.60214 -163.89985 90)
		(property "Reference" "R536"
			(at -131.03606 -3.553968 90)
			(unlocked yes)
			(layer "F.SilkS")
			(effects
				(font
					(size 0.7874 0.5842)
					(thickness 0.1524)
				)
				(justify left)
			)
		)
		(property "Value" ""
			(at 0 0 90)
			(layer "F.Fab")
			(effects
				(font
					(size 1.27 1.27)
				)
			)
		)
		(duplicate_pad_numbers_are_jumpers no)
		(fp_line
			(start 0.7874 -0.4064)
			(end 0.7874 0.4064)
			(stroke
				(width 0.1524)
				(type default)
			)
			(layer "F.SilkS")
		)
		(fp_line
			(start -0.7874 -0.4064)
			(end 0.7874 -0.4064)
			(stroke
				(width 0.1524)
				(type default)
			)
			(layer "F.SilkS")
		)
		(fp_line
			(start 0.7874 0.4064)
			(end -0.7874 0.4064)
			(stroke
				(width 0.1524)
				(type default)
			)
			(layer "F.SilkS")
		)
		(fp_line
			(start -0.7874 0.4064)
			(end -0.7874 -0.4064)
			(stroke
				(width 0.1524)
				(type default)
			)
			(layer "F.SilkS")
		)
		(fp_poly
			(pts
				(xy -0.508 0.2794) (xy -0.508 0.2286) (xy -0.635 0.2286) (xy -0.635 -0.254) (xy -0.5334 -0.254)
				(xy -0.5334 -0.2794) (xy 0.5334 -0.2794) (xy 0.5334 -0.254) (xy 0.635 -0.254) (xy 0.635 0.254) (xy 0.5334 0.254)
				(xy 0.5334 0.2794)
			)
			(stroke
				(width 0)
				(type default)
			)
			(fill no)
			(layer "F.CrtYd")
		)
		(pad "1" smd rect
			(at 0.40005 0 90)
			(size 0.4572 0.508)
			(layers "F.Cu" "F.Mask" "F.Paste")
			(net "P3V3_NODE1")
		)
		(pad "2" smd rect
			(at -0.40005 0 90)
			(size 0.4572 0.508)
			(layers "F.Cu" "F.Mask" "F.Paste")
			(net "PU_LAN1_TDI")
		)
	)
	(footprint ""
		(layer "F.Cu")
		(at 60.785756 -14.910054 -90)
		(property "Reference" "PC82"
			(at 0.031242 7.668768 90)
			(unlocked yes)
			(layer "F.SilkS")
			(effects
				(font
					(size 0.7874 0.5842)
					(thickness 0.1524)
				)
				(justify left)
			)
		)
		(property "Value" ""
			(at 0 0 270)
			(layer "F.Fab")
			(effects
				(font
					(size 1.27 1.27)
				)
			)
		)
		(duplicate_pad_numbers_are_jumpers no)
		(fp_line
			(start -1.905 0.8636)
			(end -1.905 -0.8636)
			(stroke
				(width 0.1524)
				(type default)
			)
			(layer "F.SilkS")
		)
		(fp_line
			(start 1.905 0.8636)
			(end -1.905 0.8636)
			(stroke
				(width 0.1524)
				(type default)
			)
			(layer "F.SilkS")
		)
		(fp_line
			(start 0 0.8382)
			(end 0 -0.8382)
			(stroke
				(width 0.1524)
				(type default)
			)
			(layer "F.SilkS")
		)
		(fp_line
			(start -1.905 -0.8636)
			(end 1.905 -0.8636)
			(stroke
				(width 0.1524)
				(type default)
			)
			(layer "F.SilkS")
		)
		(fp_line
			(start 1.905 -0.8636)
			(end 1.905 0.8636)
			(stroke
				(width 0.1524)
				(type default)
			)
			(layer "F.SilkS")
		)
		(fp_rect
			(start -1.524 0.7366)
			(end 1.524 -0.7366)
			(stroke
				(width 0)
				(type default)
			)
			(fill no)
			(layer "F.CrtYd")
		)
		(pad "1" smd rect
			(at 0.94996 0 270)
			(size 1.1176 1.3716)
			(layers "F.Cu" "F.Mask" "F.Paste")
			(net "PV_VDDR_NODE1")
		)
		(pad "2" smd rect
			(at -0.94996 0 270)
			(size 1.1176 1.3716)
			(layers "F.Cu" "F.Mask" "F.Paste")
			(net "GND")
		)
	)
	(footprint ""
		(layer "F.Cu")
		(at 19.38528 -43.84167 180)
		(property "Reference" "R640"
			(at -2.55524 -0.188468 0)
			(unlocked yes)
			(layer "F.SilkS")
			(effects
				(font
					(size 0.7874 0.5842)
					(thickness 0.1524)
				)
				(justify left)
			)
		)
		(property "Value" ""
			(at 0 0 180)
			(layer "F.Fab")
			(effects
				(font
					(size 1.27 1.27)
				)
			)
		)
		(duplicate_pad_numbers_are_jumpers no)
		(fp_line
			(start 0.7874 0.4064)
			(end -0.7874 0.4064)
			(stroke
				(width 0.1524)
				(type default)
			)
			(layer "F.SilkS")
		)
		(fp_line
			(start 0.7874 -0.4064)
			(end 0.7874 0.4064)
			(stroke
				(width 0.1524)
				(type default)
			)
			(layer "F.SilkS")
		)
		(fp_line
			(start -0.7874 0.4064)
			(end -0.7874 -0.4064)
			(stroke
				(width 0.1524)
				(type default)
			)
			(layer "F.SilkS")
		)
		(fp_line
			(start -0.7874 -0.4064)
			(end 0.7874 -0.4064)
			(stroke
				(width 0.1524)
				(type default)
			)
			(layer "F.SilkS")
		)
		(fp_poly
			(pts
				(xy -0.508 0.2794) (xy -0.508 0.2286) (xy -0.635 0.2286) (xy -0.635 -0.254) (xy -0.5334 -0.254)
				(xy -0.5334 -0.2794) (xy 0.5334 -0.2794) (xy 0.5334 -0.254) (xy 0.635 -0.254) (xy 0.635 0.254) (xy 0.5334 0.254)
				(xy 0.5334 0.2794)
			)
			(stroke
				(width 0)
				(type default)
			)
			(fill no)
			(layer "F.CrtYd")
		)
		(pad "1" smd rect
			(at 0.40005 0 180)
			(size 0.4572 0.508)
			(layers "F.Cu" "F.Mask" "F.Paste")
			(net "CRT_R_L")
		)
		(pad "2" smd rect
			(at -0.40005 0 180)
			(size 0.4572 0.508)
			(layers "F.Cu" "F.Mask" "F.Paste")
			(net "GND")
		)
	)
	(footprint ""
		(layer "F.Cu")
		(at 70.192138 -114.300254 90)
		(property "Reference" "R1114"
			(at -0.401066 0.513842 0)
			(unlocked yes)
			(layer "F.SilkS")
			(effects
				(font
					(size 0.7874 0.5842)
					(thickness 0.1524)
				)
				(justify left)
			)
		)
		(property "Value" ""
			(at 0 0 90)
			(layer "F.Fab")
			(effects
				(font
					(size 1.27 1.27)
				)
			)
		)
		(duplicate_pad_numbers_are_jumpers no)
		(fp_line
			(start 0.7874 -0.4064)
			(end 0.7874 0.4064)
			(stroke
				(width 0.1524)
				(type default)
			)
			(layer "F.SilkS")
		)
		(fp_line
			(start -0.7874 -0.4064)
			(end 0.7874 -0.4064)
			(stroke
				(width 0.1524)
				(type default)
			)
			(layer "F.SilkS")
		)
		(fp_line
			(start 0.7874 0.4064)
			(end -0.7874 0.4064)
			(stroke
				(width 0.1524)
				(type default)
			)
			(layer "F.SilkS")
		)
		(fp_line
			(start -0.7874 0.4064)
			(end -0.7874 -0.4064)
			(stroke
				(width 0.1524)
				(type default)
			)
			(layer "F.SilkS")
		)
		(fp_poly
			(pts
				(xy -0.508 0.2794) (xy -0.508 0.2286) (xy -0.635 0.2286) (xy -0.635 -0.254) (xy -0.5334 -0.254)
				(xy -0.5334 -0.2794) (xy 0.5334 -0.2794) (xy 0.5334 -0.254) (xy 0.635 -0.254) (xy 0.635 0.254) (xy 0.5334 0.254)
				(xy 0.5334 0.2794)
			)
			(stroke
				(width 0)
				(type default)
			)
			(fill no)
			(layer "F.CrtYd")
		)
		(pad "1" smd rect
			(at 0.40005 0 90)
			(size 0.4572 0.508)
			(layers "F.Cu" "F.Mask" "F.Paste")
			(net "GND")
		)
		(pad "2" smd rect
			(at -0.40005 0 90)
			(size 0.4572 0.508)
			(layers "F.Cu" "F.Mask" "F.Paste")
			(net "P1V8_NODE1")
		)
	)
	(footprint ""
		(layer "F.Cu")
		(at 109.45876 -188.126624 90)
		(property "Reference" "C653"
			(at 5.151882 0.791972 90)
			(unlocked yes)
			(layer "F.SilkS")
			(effects
				(font
					(size 0.7874 0.5842)
					(thickness 0.1524)
				)
				(justify left)
			)
		)
		(property "Value" ""
			(at 0 0 90)
			(layer "F.Fab")
			(effects
				(font
					(size 1.27 1.27)
				)
			)
		)
		(duplicate_pad_numbers_are_jumpers no)
		(fp_line
			(start 0.7874 -0.4064)
			(end 0.7874 0.4064)
			(stroke
				(width 0.1524)
				(type default)
			)
			(layer "F.SilkS")
		)
		(fp_line
			(start -0.7874 -0.4064)
			(end 0.7874 -0.4064)
			(stroke
				(width 0.1524)
				(type default)
			)
			(layer "F.SilkS")
		)
		(fp_line
			(start 0 0.381)
			(end 0 -0.381)
			(stroke
				(width 0.1524)
				(type default)
			)
			(layer "F.SilkS")
		)
		(fp_line
			(start 0.7874 0.4064)
			(end -0.7874 0.4064)
			(stroke
				(width 0.1524)
				(type default)
			)
			(layer "F.SilkS")
		)
		(fp_line
			(start -0.7874 0.4064)
			(end -0.7874 -0.4064)
			(stroke
				(width 0.1524)
				(type default)
			)
			(layer "F.SilkS")
		)
		(fp_poly
			(pts
				(xy -0.5334 0.254) (xy -0.635 0.254) (xy -0.635 0.2286) (xy -0.635 -0.254) (xy -0.5334 -0.254) (xy -0.5334 -0.2794)
				(xy 0.5334 -0.2794) (xy 0.5334 -0.254) (xy 0.635 -0.254) (xy 0.635 0.254) (xy 0.5334 0.254) (xy 0.5334 0.2794)
				(xy -0.508 0.2794) (xy -0.5334 0.2794)
			)
			(stroke
				(width 0)
				(type default)
			)
			(fill no)
			(layer "F.CrtYd")
		)
		(pad "1" smd rect
			(at 0.40005 0 90)
			(size 0.4572 0.508)
			(layers "F.Cu" "F.Mask" "F.Paste")
			(net "T6_NODE3_EN_R")
		)
		(pad "2" smd rect
			(at -0.40005 0 90)
			(size 0.4572 0.508)
			(layers "F.Cu" "F.Mask" "F.Paste")
			(net "GND")
		)
	)
	(footprint ""
		(layer "F.Cu")
		(at 187.579 -120.65)
		(property "Reference" "R1285"
			(at 5.588 19.07667 0)
			(unlocked yes)
			(layer "F.SilkS")
			(effects
				(font
					(size 0.7874 0.5842)
					(thickness 0.1524)
				)
				(justify left)
			)
		)
		(property "Value" ""
			(at 0 0 0)
			(layer "F.Fab")
			(effects
				(font
					(size 1.27 1.27)
				)
			)
		)
		(duplicate_pad_numbers_are_jumpers no)
		(fp_line
			(start -0.7874 -0.4064)
			(end 0.7874 -0.4064)
			(stroke
				(width 0.1524)
				(type default)
			)
			(layer "F.SilkS")
		)
		(fp_line
			(start -0.7874 0.4064)
			(end -0.7874 -0.4064)
			(stroke
				(width 0.1524)
				(type default)
			)
			(layer "F.SilkS")
		)
		(fp_line
			(start 0.7874 -0.4064)
			(end 0.7874 0.4064)
			(stroke
				(width 0.1524)
				(type default)
			)
			(layer "F.SilkS")
		)
		(fp_line
			(start 0.7874 0.4064)
			(end -0.7874 0.4064)
			(stroke
				(width 0.1524)
				(type default)
			)
			(layer "F.SilkS")
		)
		(fp_poly
			(pts
				(xy -0.508 0.2794) (xy -0.508 0.2286) (xy -0.635 0.2286) (xy -0.635 -0.254) (xy -0.5334 -0.254)
				(xy -0.5334 -0.2794) (xy 0.5334 -0.2794) (xy 0.5334 -0.254) (xy 0.635 -0.254) (xy 0.635 0.254) (xy 0.5334 0.254)
				(xy 0.5334 0.2794)
			)
			(stroke
				(width 0)
				(type default)
			)
			(fill no)
			(layer "F.CrtYd")
		)
		(pad "1" smd rect
			(at 0.40005 0)
			(size 0.4572 0.508)
			(layers "F.Cu" "F.Mask" "F.Paste")
			(net "SIO_JTAG_CPLD1_TDI")
		)
		(pad "2" smd rect
			(at -0.40005 0)
			(size 0.4572 0.508)
			(layers "F.Cu" "F.Mask" "F.Paste")
			(net "JTAG_CPLD1_TDI")
		)
	)
	(footprint ""
		(layer "F.Cu")
		(at 124.391166 -57.900062 180)
		(property "Reference" "R1217"
			(at 4.614418 0.49149 0)
			(unlocked yes)
			(layer "F.SilkS")
			(effects
				(font
					(size 0.7874 0.5842)
					(thickness 0.1524)
				)
				(justify left)
			)
		)
		(property "Value" ""
			(at 0 0 180)
			(layer "F.Fab")
			(effects
				(font
					(size 1.27 1.27)
				)
			)
		)
		(duplicate_pad_numbers_are_jumpers no)
		(fp_line
			(start 0.7874 0.4064)
			(end -0.7874 0.4064)
			(stroke
				(width 0.1524)
				(type default)
			)
			(layer "F.SilkS")
		)
		(fp_line
			(start 0.7874 -0.4064)
			(end 0.7874 0.4064)
			(stroke
				(width 0.1524)
				(type default)
			)
			(layer "F.SilkS")
		)
		(fp_line
			(start -0.7874 0.4064)
			(end -0.7874 -0.4064)
			(stroke
				(width 0.1524)
				(type default)
			)
			(layer "F.SilkS")
		)
		(fp_line
			(start -0.7874 -0.4064)
			(end 0.7874 -0.4064)
			(stroke
				(width 0.1524)
				(type default)
			)
			(layer "F.SilkS")
		)
		(fp_poly
			(pts
				(xy -0.508 0.2794) (xy -0.508 0.2286) (xy -0.635 0.2286) (xy -0.635 -0.254) (xy -0.5334 -0.254)
				(xy -0.5334 -0.2794) (xy 0.5334 -0.2794) (xy 0.5334 -0.254) (xy 0.635 -0.254) (xy 0.635 0.254) (xy 0.5334 0.254)
				(xy 0.5334 0.2794)
			)
			(stroke
				(width 0)
				(type default)
			)
			(fill no)
			(layer "F.CrtYd")
		)
		(pad "1" smd rect
			(at 0.40005 0 180)
			(size 0.4572 0.508)
			(layers "F.Cu" "F.Mask" "F.Paste")
			(net "COM4_EN_N")
		)
		(pad "2" smd rect
			(at -0.40005 0 180)
			(size 0.4572 0.508)
			(layers "F.Cu" "F.Mask" "F.Paste")
			(net "P3V3_NODE1")
		)
	)
)
